(kicad_pcb
	(version 20260206)
	(generator "pcbnew")
	(generator_version "10.0")
	(general
		(thickness 1.6)
		(legacy_teardrops no)
	)
	(paper "A4")
	(title_block
		(title "v1-tray-backplane — T6M_tray_BP_c_1023_1120.brd")
		(comment 1 "Open CloudServer (Microsoft) / footprints 159-164 of 170")
	)
	(layers
		(0 "F.Cu" signal "TOP")
		(4 "In1.Cu" signal "GND")
		(6 "In2.Cu" signal "IN1")
		(8 "In3.Cu" signal "VCC")
		(10 "In4.Cu" signal "VCC1")
		(12 "In5.Cu" signal "IN2")
		(14 "In6.Cu" signal "GND1")
		(2 "B.Cu" signal "BOTTOM")
		(9 "F.Adhes" user "F.Adhesive")
		(11 "B.Adhes" user "B.Adhesive")
		(13 "F.Paste" user "Package Geometry/Pastemask Top")
		(15 "B.Paste" user "Package Geometry/Pastemask Bottom")
		(5 "F.SilkS" user "Ref Des/Silkscreen Top")
		(7 "B.SilkS" user "Ref Des/Silkscreen Bottom")
		(1 "F.Mask" user "Board Geometry/Soldermask Top")
		(3 "B.Mask" user "Board Geometry/Soldermask Bottom")
		(17 "Dwgs.User" user "User.Drawings")
		(19 "Cmts.User" user "User.Comments")
		(21 "Eco1.User" user "User.Eco1")
		(23 "Eco2.User" user "User.Eco2")
		(25 "Edge.Cuts" user "Board Geometry/Outline")
		(27 "Margin" user)
		(31 "F.CrtYd" user "Package Geometry/Place Bound Top")
		(29 "B.CrtYd" user "Package Geometry/Place Bound Bottom")
		(35 "F.Fab" user "Ref Des/Assembly Top")
		(33 "B.Fab" user "Ref Des/Assembly Bottom")
	)
	(footprint ""
		(layer "F.Cu")
		(at 104.570022 -14.389862 180)
		(property "Reference" "U6"
			(at -5.134356 -8.113776 0)
			(unlocked yes)
			(layer "F.SilkS")
			(effects
				(font
					(size 0.7874 0.5842)
					(thickness 0.1524)
				)
				(justify left)
			)
		)
		(property "Value" ""
			(at 0 0 180)
			(layer "F.Fab")
			(effects
				(font
					(size 1.27 1.27)
				)
			)
		)
		(duplicate_pad_numbers_are_jumpers no)
		(fp_line
			(start 5.500116 3.700018)
			(end 4.191 3.700018)
			(stroke
				(width 0.1524)
				(type default)
			)
			(layer "F.SilkS")
		)
		(fp_line
			(start 5.500116 0.889)
			(end 5.500116 3.700018)
			(stroke
				(width 0.1524)
				(type default)
			)
			(layer "F.SilkS")
		)
		(fp_line
			(start 5.500116 -3.700018)
			(end 5.500116 -0.889)
			(stroke
				(width 0.1524)
				(type default)
			)
			(layer "F.SilkS")
		)
		(fp_line
			(start 3.7846 -3.700018)
			(end 5.500116 -3.700018)
			(stroke
				(width 0.1524)
				(type default)
			)
			(layer "F.SilkS")
		)
		(fp_line
			(start -3.7846 3.700018)
			(end -5.500116 3.700018)
			(stroke
				(width 0.1524)
				(type default)
			)
			(layer "F.SilkS")
		)
		(fp_line
			(start -5.500116 0.635)
			(end -5.500116 3.700018)
			(stroke
				(width 0.1524)
				(type default)
			)
			(layer "F.SilkS")
		)
		(fp_line
			(start -5.500116 -3.700018)
			(end -4.191 -3.700018)
			(stroke
				(width 0.1524)
				(type default)
			)
			(layer "F.SilkS")
		)
		(fp_line
			(start -5.500116 -3.700018)
			(end -5.500116 -0.635)
			(stroke
				(width 0.1524)
				(type default)
			)
			(layer "F.SilkS")
		)
		(fp_poly
			(pts
				(xy -3.387344 5.3848) (xy -3.946144 6.8072) (xy -2.853944 6.8072)
			)
			(stroke
				(width 0)
				(type default)
			)
			(fill yes)
			(layer "F.SilkS")
		)
		(fp_poly
			(pts
				(arc
					(start -4.064 -0.3302)
					(mid -4.8006 -1.0668)
					(end -5.5372 -0.3302)
				)
				(arc
					(start -5.5372 0.3048)
					(mid -5.314015 0.843615)
					(end -4.7752 1.0668)
				)
				(arc
					(start -4.7752 1.0668)
					(mid -4.272306 0.858494)
					(end -4.064 0.3556)
				)
			)
			(stroke
				(width 0)
				(type default)
			)
			(fill no)
			(layer "B.CrtYd")
		)
		(fp_poly
			(pts
				(arc
					(start 3.7338 0)
					(mid 5.8674 0)
					(end 3.7338 0)
				)
			)
			(stroke
				(width 0)
				(type default)
			)
			(fill no)
			(layer "B.CrtYd")
		)
		(fp_rect
			(start -5.5118 5.1308)
			(end 5.5118 -5.1308)
			(stroke
				(width 0)
				(type default)
			)
			(fill no)
			(layer "F.CrtYd")
		)
		(fp_text user "10"
			(at 5.776214 5.877306 0)
			(unlocked yes)
			(layer "F.SilkS")
			(effects
				(font
					(size 0.7874 0.5842)
					(thickness 0.1524)
				)
				(justify left)
			)
		)
		(fp_text user "11"
			(at 3.19659 -6.426454 90)
			(unlocked yes)
			(layer "F.SilkS")
			(effects
				(font
					(size 0.7874 0.5842)
					(thickness 0.1524)
				)
				(justify left)
			)
		)
		(fp_text user "20"
			(at -3.99161 -8.483854 90)
			(unlocked yes)
			(layer "F.SilkS")
			(effects
				(font
					(size 0.7874 0.5842)
					(thickness 0.1524)
				)
				(justify left)
			)
		)
		(fp_text user "1"
			(at -4.148582 5.851906 0)
			(unlocked yes)
			(layer "F.SilkS")
			(effects
				(font
					(size 0.7874 0.5842)
					(thickness 0.1524)
				)
				(justify left)
			)
		)
		(pad "" np_thru_hole oval
			(at -4.800092 0 180)
			(size 0.9652 1.6002)
			(drill oval 0.9652 1.6002)
			(layers "*.Cu" "*.Mask")
			(clearance 0.381)
			(thermal_gap 0.381)
		)
		(pad "" np_thru_hole circle
			(at 4.800092 0 180)
			(size 1.6002 1.6002)
			(drill 1.6002)
			(layers "*.Cu" "*.Mask")
			(clearance 0.381)
			(thermal_gap 0.381)
		)
		(pad "1" smd oval
			(at -3.400044 4.100068 180)
			(size 0.508 2.032)
			(layers "F.Cu" "F.Mask" "F.Paste")
			(net "GND")
		)
		(pad "2" smd oval
			(at -2.599944 4.100068 180)
			(size 0.508 2.032)
			(layers "F.Cu" "F.Mask" "F.Paste")
			(net "ENET10G_2_TX_FAULT")
		)
		(pad "3" smd oval
			(at -1.800098 4.100068 180)
			(size 0.508 2.032)
			(layers "F.Cu" "F.Mask" "F.Paste")
			(net "ENET10G_2_TX_DIS")
		)
		(pad "4" smd oval
			(at -0.999998 4.100068 180)
			(size 0.508 2.032)
			(layers "F.Cu" "F.Mask" "F.Paste")
			(net "ENET10G_2_SDA")
		)
		(pad "5" smd oval
			(at -0.199898 4.100068 180)
			(size 0.508 2.032)
			(layers "F.Cu" "F.Mask" "F.Paste")
			(net "ENET10G_2_SCL")
		)
		(pad "6" smd oval
			(at 0.599948 4.100068 180)
			(size 0.508 2.032)
			(layers "F.Cu" "F.Mask" "F.Paste")
			(net "ENET10G_2_MOD_DEF0")
		)
		(pad "7" smd oval
			(at 1.400048 4.100068 180)
			(size 0.508 2.032)
			(layers "F.Cu" "F.Mask" "F.Paste")
			(net "ENET10G_2_RS0")
		)
		(pad "8" smd oval
			(at 2.199894 4.100068 180)
			(size 0.508 2.032)
			(layers "F.Cu" "F.Mask" "F.Paste")
			(net "ENET10G_2_LOS")
		)
		(pad "9" smd oval
			(at 2.999994 4.100068 180)
			(size 0.508 2.032)
			(layers "F.Cu" "F.Mask" "F.Paste")
			(net "ENET10G_2_RS1")
		)
		(pad "10" smd oval
			(at 3.800094 4.100068 180)
			(size 0.508 2.032)
			(layers "F.Cu" "F.Mask" "F.Paste")
			(net "GND")
		)
		(pad "11" smd oval
			(at 3.400044 -4.100068 180)
			(size 0.508 2.032)
			(layers "F.Cu" "F.Mask" "F.Paste")
			(net "GND")
		)
		(pad "12" smd oval
			(at 2.599944 -4.100068 180)
			(size 0.508 2.032)
			(layers "F.Cu" "F.Mask" "F.Paste")
			(net "ENET10G_2_RDN")
		)
		(pad "13" smd oval
			(at 1.800098 -4.100068 180)
			(size 0.508 2.032)
			(layers "F.Cu" "F.Mask" "F.Paste")
			(net "ENET10G_2_RDP")
		)
		(pad "14" smd oval
			(at 0.999998 -4.100068 180)
			(size 0.508 2.032)
			(layers "F.Cu" "F.Mask" "F.Paste")
			(net "GND")
		)
		(pad "15" smd oval
			(at 0.199898 -4.100068 180)
			(size 0.508 2.032)
			(layers "F.Cu" "F.Mask" "F.Paste")
			(net "P3V3_10G_2_VCCR")
		)
		(pad "16" smd oval
			(at -0.599948 -4.100068 180)
			(size 0.508 2.032)
			(layers "F.Cu" "F.Mask" "F.Paste")
			(net "P3V3_10G_2_VCCT")
		)
		(pad "17" smd oval
			(at -1.400048 -4.100068 180)
			(size 0.508 2.032)
			(layers "F.Cu" "F.Mask" "F.Paste")
			(net "GND")
		)
		(pad "18" smd oval
			(at -2.199894 -4.100068 180)
			(size 0.508 2.032)
			(layers "F.Cu" "F.Mask" "F.Paste")
			(net "ENET10G_2_TDP")
		)
		(pad "19" smd oval
			(at -2.999994 -4.100068 180)
			(size 0.508 2.032)
			(layers "F.Cu" "F.Mask" "F.Paste")
			(net "ENET10G_2_TDN")
		)
		(pad "20" smd oval
			(at -3.800094 -4.100068 180)
			(size 0.508 2.032)
			(layers "F.Cu" "F.Mask" "F.Paste")
			(net "GND")
		)
		(zone
			(layers "F.Cu" "B.Cu" "In1.Cu" "In2.Cu" "In3.Cu" "In4.Cu" "In5.Cu" "In6.Cu")
			(hatch none 0.5)
			(connect_pads
				(clearance 0)
			)
			(min_thickness 0.25)
			(keepout
				(tracks not_allowed)
				(vias allowed)
				(pads allowed)
				(copperpour not_allowed)
				(footprints allowed)
			)
			(placement
				(enabled no)
				(sheetname "")
			)
			(fill
				(thermal_gap 0.5)
				(thermal_bridge_width 0.5)
				(island_removal_mode 0)
			)
			(polygon
				(pts
					(arc
						(start 109.345222 -15.609062)
						(mid 109.9918 -15.34124)
						(end 110.259622 -14.694662)
					)
					(arc
						(start 110.259622 -14.059662)
						(mid 109.370622 -13.170662)
						(end 108.481622 -14.059662)
					)
					(arc
						(start 108.481622 -14.745462)
						(mid 108.734565 -15.356119)
						(end 109.345222 -15.609062)
					)
				)
			)
		)
		(zone
			(layers "F.Cu" "B.Cu" "In1.Cu" "In2.Cu" "In3.Cu" "In4.Cu" "In5.Cu" "In6.Cu")
			(hatch none 0.5)
			(connect_pads
				(clearance 0)
			)
			(min_thickness 0.25)
			(keepout
				(tracks not_allowed)
				(vias allowed)
				(pads allowed)
				(copperpour not_allowed)
				(footprints allowed)
			)
			(placement
				(enabled no)
				(sheetname "")
			)
			(fill
				(thermal_gap 0.5)
				(thermal_bridge_width 0.5)
				(island_removal_mode 0)
			)
			(polygon
				(pts
					(arc
						(start 100.988622 -14.389862)
						(mid 98.550222 -14.389862)
						(end 100.988622 -14.389862)
					)
				)
			)
		)
	)
	(footprint ""
		(layer "F.Cu")
		(at 323.2404 -2.6416 90)
		(property "Reference" "C31"
			(at -1.6002 -3.038348 90)
			(unlocked yes)
			(layer "F.SilkS")
			(effects
				(font
					(size 0.7874 0.5842)
					(thickness 0.1524)
				)
				(justify left)
			)
		)
		(property "Value" ""
			(at 0 0 90)
			(layer "F.Fab")
			(effects
				(font
					(size 1.27 1.27)
				)
			)
		)
		(duplicate_pad_numbers_are_jumpers no)
		(fp_line
			(start 0.7874 -0.4064)
			(end 0.7874 0.4064)
			(stroke
				(width 0.1524)
				(type default)
			)
			(layer "F.SilkS")
		)
		(fp_line
			(start -0.7874 -0.4064)
			(end 0.7874 -0.4064)
			(stroke
				(width 0.1524)
				(type default)
			)
			(layer "F.SilkS")
		)
		(fp_line
			(start 0 0.381)
			(end 0 -0.381)
			(stroke
				(width 0.1524)
				(type default)
			)
			(layer "F.SilkS")
		)
		(fp_line
			(start 0.7874 0.4064)
			(end -0.7874 0.4064)
			(stroke
				(width 0.1524)
				(type default)
			)
			(layer "F.SilkS")
		)
		(fp_line
			(start -0.7874 0.4064)
			(end -0.7874 -0.4064)
			(stroke
				(width 0.1524)
				(type default)
			)
			(layer "F.SilkS")
		)
		(fp_poly
			(pts
				(xy -0.5334 0.254) (xy -0.635 0.254) (xy -0.635 0.2286) (xy -0.635 -0.254) (xy -0.5334 -0.254) (xy -0.5334 -0.2794)
				(xy 0.5334 -0.2794) (xy 0.5334 -0.254) (xy 0.635 -0.254) (xy 0.635 0.254) (xy 0.5334 0.254) (xy 0.5334 0.2794)
				(xy -0.508 0.2794) (xy -0.5334 0.2794)
			)
			(stroke
				(width 0)
				(type default)
			)
			(fill no)
			(layer "F.CrtYd")
		)
		(pad "1" smd rect
			(at 0.40005 0 90)
			(size 0.4572 0.508)
			(layers "F.Cu" "F.Mask" "F.Paste")
			(net "P3V3_10G_4_VCCR")
		)
		(pad "2" smd rect
			(at -0.40005 0 90)
			(size 0.4572 0.508)
			(layers "F.Cu" "F.Mask" "F.Paste")
			(net "GND")
		)
	)
	(footprint ""
		(layer "F.Cu")
		(at 154.89936 -26.709878 180)
		(property "Reference" "R15"
			(at -33.73628 -17.945608 0)
			(unlocked yes)
			(layer "F.SilkS")
			(effects
				(font
					(size 0.7874 0.5842)
					(thickness 0.1524)
				)
				(justify left)
			)
		)
		(property "Value" ""
			(at 0 0 180)
			(layer "F.Fab")
			(effects
				(font
					(size 1.27 1.27)
				)
			)
		)
		(duplicate_pad_numbers_are_jumpers no)
		(fp_line
			(start 0.7874 0.4064)
			(end -0.7874 0.4064)
			(stroke
				(width 0.1524)
				(type default)
			)
			(layer "F.SilkS")
		)
		(fp_line
			(start 0.7874 -0.4064)
			(end 0.7874 0.4064)
			(stroke
				(width 0.1524)
				(type default)
			)
			(layer "F.SilkS")
		)
		(fp_line
			(start -0.7874 0.4064)
			(end -0.7874 -0.4064)
			(stroke
				(width 0.1524)
				(type default)
			)
			(layer "F.SilkS")
		)
		(fp_line
			(start -0.7874 -0.4064)
			(end 0.7874 -0.4064)
			(stroke
				(width 0.1524)
				(type default)
			)
			(layer "F.SilkS")
		)
		(fp_poly
			(pts
				(xy -0.508 0.2794) (xy -0.508 0.2286) (xy -0.635 0.2286) (xy -0.635 -0.254) (xy -0.5334 -0.254)
				(xy -0.5334 -0.2794) (xy 0.5334 -0.2794) (xy 0.5334 -0.254) (xy 0.635 -0.254) (xy 0.635 0.254) (xy 0.5334 0.254)
				(xy 0.5334 0.2794)
			)
			(stroke
				(width 0)
				(type default)
			)
			(fill no)
			(layer "F.CrtYd")
		)
		(pad "1" smd rect
			(at 0.40005 0 180)
			(size 0.4572 0.508)
			(layers "F.Cu" "F.Mask" "F.Paste")
			(net "P3V3_BLAD1")
		)
		(pad "2" smd rect
			(at -0.40005 0 180)
			(size 0.4572 0.508)
			(layers "F.Cu" "F.Mask" "F.Paste")
			(net "ENET10G_1_RS1")
		)
	)
	(footprint ""
		(layer "F.Cu")
		(at 310.749696 -23.520146 -90)
		(property "Reference" "C9"
			(at -1.854708 5.446522 90)
			(unlocked yes)
			(layer "F.SilkS")
			(effects
				(font
					(size 0.7874 0.5842)
					(thickness 0.1524)
				)
			)
		)
		(property "Value" ""
			(at 0 0 270)
			(layer "F.Fab")
			(effects
				(font
					(size 1.27 1.27)
				)
			)
		)
		(duplicate_pad_numbers_are_jumpers no)
		(fp_line
			(start -1.2954 0.5842)
			(end -1.2954 -0.5842)
			(stroke
				(width 0.1524)
				(type default)
			)
			(layer "F.SilkS")
		)
		(fp_line
			(start 1.2954 0.5842)
			(end -1.2954 0.5842)
			(stroke
				(width 0.1524)
				(type default)
			)
			(layer "F.SilkS")
		)
		(fp_line
			(start -1.2954 -0.5842)
			(end 1.2954 -0.5842)
			(stroke
				(width 0.1524)
				(type default)
			)
			(layer "F.SilkS")
		)
		(fp_line
			(start 0 -0.5842)
			(end 0 0.5842)
			(stroke
				(width 0.1524)
				(type default)
			)
			(layer "F.SilkS")
		)
		(fp_line
			(start 1.2954 -0.5842)
			(end 1.2954 0.5842)
			(stroke
				(width 0.1524)
				(type default)
			)
			(layer "F.SilkS")
		)
		(fp_poly
			(pts
				(xy 0.8636 -0.4572) (xy 0.8636 -0.3556) (xy 1.143 -0.3556) (xy 1.143 0.3556) (xy 0.8636 0.3556)
				(xy 0.8636 0.4572) (xy -0.8636 0.4572) (xy -0.8636 0.3556) (xy -1.143 0.3556) (xy -1.143 -0.3556)
				(xy -0.8636 -0.3556) (xy -0.8636 -0.4572)
			)
			(stroke
				(width 0)
				(type default)
			)
			(fill no)
			(layer "F.CrtYd")
		)
		(fp_line
			(start -0.884936 0.504952)
			(end -0.884936 -0.504952)
			(stroke
				(width 0.1)
				(type default)
			)
			(layer "F.Fab")
		)
		(fp_line
			(start 0.884936 0.504952)
			(end -0.884936 0.504952)
			(stroke
				(width 0.1)
				(type default)
			)
			(layer "F.Fab")
		)
		(fp_line
			(start -0.884936 -0.504952)
			(end 0.884936 -0.504952)
			(stroke
				(width 0.1)
				(type default)
			)
			(layer "F.Fab")
		)
		(fp_line
			(start 0.884936 -0.504952)
			(end 0.884936 0.504952)
			(stroke
				(width 0.1)
				(type default)
			)
			(layer "F.Fab")
		)
		(pad "1" smd rect
			(at 0.7366 0)
			(size 0.7112 0.8128)
			(layers "F.Cu" "F.Mask" "F.Paste")
			(net "P12V")
		)
		(pad "2" smd rect
			(at -0.7366 0)
			(size 0.7112 0.8128)
			(layers "F.Cu" "F.Mask" "F.Paste")
			(net "GND")
		)
	)
	(footprint ""
		(layer "F.Cu")
		(at 342.965278 -21.78304 90)
		(property "Reference" "R36"
			(at 3.227578 -56.835548 90)
			(unlocked yes)
			(layer "F.SilkS")
			(effects
				(font
					(size 0.7874 0.5842)
					(thickness 0.1524)
				)
				(justify left)
			)
		)
		(property "Value" ""
			(at 0 0 90)
			(layer "F.Fab")
			(effects
				(font
					(size 1.27 1.27)
				)
			)
		)
		(duplicate_pad_numbers_are_jumpers no)
		(fp_line
			(start 0.7874 -0.4064)
			(end 0.7874 0.4064)
			(stroke
				(width 0.1524)
				(type default)
			)
			(layer "F.SilkS")
		)
		(fp_line
			(start -0.7874 -0.4064)
			(end 0.7874 -0.4064)
			(stroke
				(width 0.1524)
				(type default)
			)
			(layer "F.SilkS")
		)
		(fp_line
			(start 0.7874 0.4064)
			(end -0.7874 0.4064)
			(stroke
				(width 0.1524)
				(type default)
			)
			(layer "F.SilkS")
		)
		(fp_line
			(start -0.7874 0.4064)
			(end -0.7874 -0.4064)
			(stroke
				(width 0.1524)
				(type default)
			)
			(layer "F.SilkS")
		)
		(fp_poly
			(pts
				(xy -0.508 0.2794) (xy -0.508 0.2286) (xy -0.635 0.2286) (xy -0.635 -0.254) (xy -0.5334 -0.254)
				(xy -0.5334 -0.2794) (xy 0.5334 -0.2794) (xy 0.5334 -0.254) (xy 0.635 -0.254) (xy 0.635 0.254) (xy 0.5334 0.254)
				(xy 0.5334 0.2794)
			)
			(stroke
				(width 0)
				(type default)
			)
			(fill no)
			(layer "F.CrtYd")
		)
		(pad "1" smd rect
			(at 0.40005 0 90)
			(size 0.4572 0.508)
			(layers "F.Cu" "F.Mask" "F.Paste")
			(net "GND")
		)
		(pad "2" smd rect
			(at -0.40005 0 90)
			(size 0.4572 0.508)
			(layers "F.Cu" "F.Mask" "F.Paste")
			(net "BLADE2_MATED_N")
		)
	)
	(footprint ""
		(layer "F.Cu")
		(at 92.16644 -27.574494)
		(property "Reference" "R12"
			(at -7.112 0.593852 0)
			(unlocked yes)
			(layer "F.SilkS")
			(effects
				(font
					(size 0.7874 0.5842)
					(thickness 0.1524)
				)
				(justify left)
			)
		)
		(property "Value" ""
			(at 0 0 0)
			(layer "F.Fab")
			(effects
				(font
					(size 1.27 1.27)
				)
			)
		)
		(duplicate_pad_numbers_are_jumpers no)
		(fp_line
			(start -0.7874 -0.4064)
			(end 0.7874 -0.4064)
			(stroke
				(width 0.1524)
				(type default)
			)
			(layer "F.SilkS")
		)
		(fp_line
			(start -0.7874 0.4064)
			(end -0.7874 -0.4064)
			(stroke
				(width 0.1524)
				(type default)
			)
			(layer "F.SilkS")
		)
		(fp_line
			(start 0.7874 -0.4064)
			(end 0.7874 0.4064)
			(stroke
				(width 0.1524)
				(type default)
			)
			(layer "F.SilkS")
		)
		(fp_line
			(start 0.7874 0.4064)
			(end -0.7874 0.4064)
			(stroke
				(width 0.1524)
				(type default)
			)
			(layer "F.SilkS")
		)
		(fp_poly
			(pts
				(xy -0.508 0.2794) (xy -0.508 0.2286) (xy -0.635 0.2286) (xy -0.635 -0.254) (xy -0.5334 -0.254)
				(xy -0.5334 -0.2794) (xy 0.5334 -0.2794) (xy 0.5334 -0.254) (xy 0.635 -0.254) (xy 0.635 0.254) (xy 0.5334 0.254)
				(xy 0.5334 0.2794)
			)
			(stroke
				(width 0)
				(type default)
			)
			(fill no)
			(layer "F.CrtYd")
		)
		(pad "1" smd rect
			(at 0.40005 0)
			(size 0.4572 0.508)
			(layers "F.Cu" "F.Mask" "F.Paste")
			(net "P3V3_BLAD1")
		)
		(pad "2" smd rect
			(at -0.40005 0)
			(size 0.4572 0.508)
			(layers "F.Cu" "F.Mask" "F.Paste")
			(net "ENET10G_2_RS0")
		)
	)
)
